(kicad_pcb
	(version 20260206)
	(generator "pcbnew")
	(generator_version "10.0")
	(general
		(thickness 1.6)
		(legacy_teardrops no)
	)
	(paper "A4")
	(title_block
		(title "v1-chassis-manager — T6M_CM_d_v01_1031_1645.brd")
		(comment 1 "Open CloudServer (Microsoft) / footprint 838 of 2512 (J35), pads 1-119 of 164")
	)
	(layers
		(0 "F.Cu" signal "TOP")
		(4 "In1.Cu" signal "GND1")
		(6 "In2.Cu" signal "IN1")
		(8 "In3.Cu" signal "VCC1")
		(10 "In4.Cu" signal "VCC2")
		(12 "In5.Cu" signal "GND2")
		(14 "In6.Cu" signal "IN2")
		(16 "In7.Cu" signal "IN3")
		(18 "In8.Cu" signal "GND3")
		(2 "B.Cu" signal "BOTTOM")
		(9 "F.Adhes" user "F.Adhesive")
		(11 "B.Adhes" user "B.Adhesive")
		(13 "F.Paste" user "Package Geometry/Pastemask Top")
		(15 "B.Paste" user "Package Geometry/Pastemask Bottom")
		(5 "F.SilkS" user "Ref Des/Silkscreen Top")
		(7 "B.SilkS" user "Ref Des/Silkscreen Bottom")
		(1 "F.Mask" user "Board Geometry/Soldermask Top")
		(3 "B.Mask" user "Board Geometry/Soldermask Bottom")
		(17 "Dwgs.User" user "User.Drawings")
		(19 "Cmts.User" user "User.Comments")
		(21 "Eco1.User" user "User.Eco1")
		(23 "Eco2.User" user "User.Eco2")
		(25 "Edge.Cuts" user "Board Geometry/Outline")
		(27 "Margin" user)
		(31 "F.CrtYd" user "Package Geometry/Place Bound Top")
		(29 "B.CrtYd" user "Package Geometry/Place Bound Bottom")
		(35 "F.Fab" user "Ref Des/Assembly Top")
		(33 "B.Fab" user "Ref Des/Assembly Bottom")
	)
	(footprint ""
		(layer "F.Cu")
		(at 54.515004 -205.199488 180)
		(property "Reference" "J35"
			(at -39.89832 -7.345934 0)
			(unlocked yes)
			(layer "F.SilkS")
			(effects
				(font
					(size 0.7874 0.5842)
					(thickness 0.1524)
				)
				(justify left)
			)
		)
		(property "Value" ""
			(at 0 0 180)
			(layer "F.Fab")
			(effects
				(font
					(size 1.27 1.27)
				)
			)
		)
		(duplicate_pad_numbers_are_jumpers no)
		(pad "A1" smd rect
			(at -41.500044 -0.499872 180)
			(size 0.762 3.2004)
			(layers "F.Cu" "F.Mask" "F.Paste")
			(net "GND")
		)
		(pad "A2" smd rect
			(at -40.500046 0 180)
			(size 0.762 4.2164)
			(layers "F.Cu" "F.Mask" "F.Paste")
			(net "T5_NODE3_EN_R")
		)
		(pad "A3" smd rect
			(at -39.500048 0 180)
			(size 0.762 4.2164)
			(layers "F.Cu" "F.Mask" "F.Paste")
			(net "T5_NODE4_EN_R")
		)
		(pad "A4" smd rect
			(at -38.50005 0 180)
			(size 0.762 4.2164)
			(layers "F.Cu" "F.Mask" "F.Paste")
			(net "GND")
		)
		(pad "A5" smd rect
			(at -37.500052 0 180)
			(size 0.762 4.2164)
			(layers "F.Cu" "F.Mask" "F.Paste")
			(net "UART_T5_NODE1_RXD_R")
		)
		(pad "A6" smd rect
			(at -36.500054 0 180)
			(size 0.762 4.2164)
			(layers "F.Cu" "F.Mask" "F.Paste")
			(net "UART_T5_NODE1_TXD_R")
		)
		(pad "A7" smd rect
			(at -35.500056 0 180)
			(size 0.762 4.2164)
			(layers "F.Cu" "F.Mask" "F.Paste")
			(net "GND")
		)
		(pad "A8" smd rect
			(at -34.500058 0 180)
			(size 0.762 4.2164)
			(layers "F.Cu" "F.Mask" "F.Paste")
			(net "UART_T5_NODE2_RXD_R")
		)
		(pad "A9" smd rect
			(at -33.50006 0 180)
			(size 0.762 4.2164)
			(layers "F.Cu" "F.Mask" "F.Paste")
			(net "UART_T5_NODE2_TXD_R")
		)
		(pad "A10" smd rect
			(at -32.500062 0 180)
			(size 0.762 4.2164)
			(layers "F.Cu" "F.Mask" "F.Paste")
			(net "UART_T5_NODE3_RXD_R")
		)
		(pad "A11" smd rect
			(at -31.500064 0 180)
			(size 0.762 4.2164)
			(layers "F.Cu" "F.Mask" "F.Paste")
			(net "UART_T5_NODE3_TXD_R")
		)
		(pad "A12" smd rect
			(at -28.50007 0 180)
			(size 0.762 4.2164)
			(layers "F.Cu" "F.Mask" "F.Paste")
			(net "UART_T5_NODE4_RXD_R")
		)
		(pad "A13" smd rect
			(at -27.500072 0 180)
			(size 0.762 4.2164)
			(layers "F.Cu" "F.Mask" "F.Paste")
			(net "UART_T5_NODE4_TXD_R")
		)
		(pad "A14" smd rect
			(at -26.500074 0 180)
			(size 0.762 4.2164)
			(layers "F.Cu" "F.Mask" "F.Paste")
			(net "GND")
		)
		(pad "A15" smd rect
			(at -25.500076 0 180)
			(size 0.762 4.2164)
			(layers "F.Cu" "F.Mask" "F.Paste")
			(net "T3_NODE1_EN_R")
		)
		(pad "A16" smd rect
			(at -24.500078 0 180)
			(size 0.762 4.2164)
			(layers "F.Cu" "F.Mask" "F.Paste")
			(net "T3_NODE2_EN_R")
		)
		(pad "A17" smd rect
			(at -23.50008 0 180)
			(size 0.762 4.2164)
			(layers "F.Cu" "F.Mask" "F.Paste")
			(net "T3_NODE3_EN_R")
		)
		(pad "A18" smd rect
			(at -22.500082 0 180)
			(size 0.762 4.2164)
			(layers "F.Cu" "F.Mask" "F.Paste")
			(net "T3_NODE4_EN_R")
		)
		(pad "A19" smd rect
			(at -21.500084 0 180)
			(size 0.762 4.2164)
			(layers "F.Cu" "F.Mask" "F.Paste")
			(net "GND")
		)
		(pad "A20" smd rect
			(at -20.500086 0 180)
			(size 0.762 4.2164)
			(layers "F.Cu" "F.Mask" "F.Paste")
			(net "UART_T3_NODE1_RXD_R")
		)
		(pad "A21" smd rect
			(at -19.500088 0 180)
			(size 0.762 4.2164)
			(layers "F.Cu" "F.Mask" "F.Paste")
			(net "UART_T3_NODE1_TXD_R")
		)
		(pad "A22" smd rect
			(at -18.50009 0 180)
			(size 0.762 4.2164)
			(layers "F.Cu" "F.Mask" "F.Paste")
			(net "UART_T3_NODE2_RXD_R")
		)
		(pad "A23" smd rect
			(at -17.500092 0 180)
			(size 0.762 4.2164)
			(layers "F.Cu" "F.Mask" "F.Paste")
			(net "UART_T3_NODE2_TXD_R")
		)
		(pad "A24" smd rect
			(at -16.500094 0 180)
			(size 0.762 4.2164)
			(layers "F.Cu" "F.Mask" "F.Paste")
			(net "GND")
		)
		(pad "A25" smd rect
			(at -15.500096 0 180)
			(size 0.762 4.2164)
			(layers "F.Cu" "F.Mask" "F.Paste")
			(net "UART_T3_NODE3_RXD_R")
		)
		(pad "A26" smd rect
			(at -14.500098 0 180)
			(size 0.762 4.2164)
			(layers "F.Cu" "F.Mask" "F.Paste")
			(net "UART_T3_NODE3_TXD_R")
		)
		(pad "A27" smd rect
			(at -13.5001 0 180)
			(size 0.762 4.2164)
			(layers "F.Cu" "F.Mask" "F.Paste")
			(net "UART_T3_NODE4_RXD_R")
		)
		(pad "A28" smd rect
			(at -12.500102 0 180)
			(size 0.762 4.2164)
			(layers "F.Cu" "F.Mask" "F.Paste")
			(net "UART_T3_NODE4_TXD_R")
		)
		(pad "A29" smd rect
			(at -11.500104 0 180)
			(size 0.762 4.2164)
			(layers "F.Cu" "F.Mask" "F.Paste")
			(net "GND")
		)
		(pad "A30" smd rect
			(at -10.500106 0 180)
			(size 0.762 4.2164)
			(layers "F.Cu" "F.Mask" "F.Paste")
			(net "T1_NODE1_EN_R")
		)
		(pad "A31" smd rect
			(at -9.500108 0 180)
			(size 0.762 4.2164)
			(layers "F.Cu" "F.Mask" "F.Paste")
			(net "T1_NODE2_EN_R")
		)
		(pad "A32" smd rect
			(at -8.50011 0 180)
			(size 0.762 4.2164)
			(layers "F.Cu" "F.Mask" "F.Paste")
			(net "T1_NODE3_EN_R")
		)
		(pad "A33" smd rect
			(at -7.500112 0 180)
			(size 0.762 4.2164)
			(layers "F.Cu" "F.Mask" "F.Paste")
			(net "T1_NODE4_EN_R")
		)
		(pad "A34" smd rect
			(at -6.500114 0 180)
			(size 0.762 4.2164)
			(layers "F.Cu" "F.Mask" "F.Paste")
			(net "GND")
		)
		(pad "A35" smd rect
			(at -5.500116 0 180)
			(size 0.762 4.2164)
			(layers "F.Cu" "F.Mask" "F.Paste")
			(net "UART_T1_NODE2_RXD_R")
		)
		(pad "A36" smd rect
			(at -4.500118 0 180)
			(size 0.762 4.2164)
			(layers "F.Cu" "F.Mask" "F.Paste")
			(net "UART_T1_NODE2_TXD_R")
		)
		(pad "A37" smd rect
			(at -3.50012 0 180)
			(size 0.762 4.2164)
			(layers "F.Cu" "F.Mask" "F.Paste")
			(net "UART_T1_NODE3_RXD_R")
		)
		(pad "A38" smd rect
			(at -2.500122 0 180)
			(size 0.762 4.2164)
			(layers "F.Cu" "F.Mask" "F.Paste")
			(net "UART_T1_NODE3_TXD_R")
		)
		(pad "A39" smd rect
			(at -1.500124 0 180)
			(size 0.762 4.2164)
			(layers "F.Cu" "F.Mask" "F.Paste")
			(net "GND")
		)
		(pad "A40" smd rect
			(at -0.499872 0 180)
			(size 0.762 4.2164)
			(layers "F.Cu" "F.Mask" "F.Paste")
			(net "UART_T1_NODE4_RXD_R")
		)
		(pad "A41" smd rect
			(at 0.499872 0 180)
			(size 0.762 4.2164)
			(layers "F.Cu" "F.Mask" "F.Paste")
			(net "UART_T1_NODE4_TXD_R")
		)
		(pad "A42" smd rect
			(at 1.500124 0 180)
			(size 0.762 4.2164)
			(layers "F.Cu" "F.Mask" "F.Paste")
			(net "UART_T1_NODE1_RXD_R")
		)
		(pad "A43" smd rect
			(at 2.500122 0 180)
			(size 0.762 4.2164)
			(layers "F.Cu" "F.Mask" "F.Paste")
			(net "UART_T1_NODE1_TXD_R")
		)
		(pad "A44" smd rect
			(at 3.50012 0 180)
			(size 0.762 4.2164)
			(layers "F.Cu" "F.Mask" "F.Paste")
			(net "GND")
		)
		(pad "A45" smd rect
			(at 4.500118 0 180)
			(size 0.762 4.2164)
			(layers "F.Cu" "F.Mask" "F.Paste")
			(net "PSU1_DC_OK_R")
		)
		(pad "A46" smd rect
			(at 5.500116 0 180)
			(size 0.762 4.2164)
			(layers "F.Cu" "F.Mask" "F.Paste")
			(net "PSU2_DC_OK_R")
		)
		(pad "A47" smd rect
			(at 6.500114 0 180)
			(size 0.762 4.2164)
			(layers "F.Cu" "F.Mask" "F.Paste")
			(net "PSU3_DC_OK_R")
		)
		(pad "A48" smd rect
			(at 7.500112 0 180)
			(size 0.762 4.2164)
			(layers "F.Cu" "F.Mask" "F.Paste")
			(net "PSU4_DC_OK_R")
		)
		(pad "A49" smd rect
			(at 8.50011 0 180)
			(size 0.762 4.2164)
			(layers "F.Cu" "F.Mask" "F.Paste")
			(net "PSU5_DC_OK_R")
		)
		(pad "A50" smd rect
			(at 9.500108 0 180)
			(size 0.762 4.2164)
			(layers "F.Cu" "F.Mask" "F.Paste")
			(net "PSU6_DC_OK_R")
		)
		(pad "A51" smd rect
			(at 10.500106 0 180)
			(size 0.762 4.2164)
			(layers "F.Cu" "F.Mask" "F.Paste")
			(net "GND")
		)
		(pad "A52" smd rect
			(at 11.500104 0 180)
			(size 0.762 4.2164)
			(layers "F.Cu" "F.Mask" "F.Paste")
			(net "UART_RTS_P6_L_N")
		)
		(pad "A53" smd rect
			(at 12.500102 0 180)
			(size 0.762 4.2164)
			(layers "F.Cu" "F.Mask" "F.Paste")
			(net "UART_DSR_P6_L_N")
		)
		(pad "A54" smd rect
			(at 13.5001 0 180)
			(size 0.762 4.2164)
			(layers "F.Cu" "F.Mask" "F.Paste")
			(net "UART_RX_P6_L")
		)
		(pad "A55" smd rect
			(at 14.500098 0 180)
			(size 0.762 4.2164)
			(layers "F.Cu" "F.Mask" "F.Paste")
			(net "UART_TX_P6_L")
		)
		(pad "A56" smd rect
			(at 15.500096 0 180)
			(size 0.762 4.2164)
			(layers "F.Cu" "F.Mask" "F.Paste")
			(net "UART_DTR_P6_L_N")
		)
		(pad "A57" smd rect
			(at 16.500094 0 180)
			(size 0.762 4.2164)
			(layers "F.Cu" "F.Mask" "F.Paste")
			(net "UART_CTS_P6_L_N")
		)
		(pad "A58" smd rect
			(at 17.500092 0 180)
			(size 0.762 4.2164)
			(layers "F.Cu" "F.Mask" "F.Paste")
			(net "UART_RI_P6_L_N_R")
		)
		(pad "A59" smd rect
			(at 18.50009 0 180)
			(size 0.762 4.2164)
			(layers "F.Cu" "F.Mask" "F.Paste")
			(net "GND")
		)
		(pad "A60" smd rect
			(at 19.500088 0 180)
			(size 0.762 4.2164)
			(layers "F.Cu" "F.Mask" "F.Paste")
			(net "UART_RTS_P2_L_N")
		)
		(pad "A61" smd rect
			(at 20.500086 0 180)
			(size 0.762 4.2164)
			(layers "F.Cu" "F.Mask" "F.Paste")
			(net "UART_DSR_P2_L_N")
		)
		(pad "A62" smd rect
			(at 21.500084 0 180)
			(size 0.762 4.2164)
			(layers "F.Cu" "F.Mask" "F.Paste")
			(net "UART_RX_P2_L")
		)
		(pad "A63" smd rect
			(at 22.500082 0 180)
			(size 0.762 4.2164)
			(layers "F.Cu" "F.Mask" "F.Paste")
			(net "UART_TX_P2_L")
		)
		(pad "A64" smd rect
			(at 23.50008 0 180)
			(size 0.762 4.2164)
			(layers "F.Cu" "F.Mask" "F.Paste")
			(net "UART_DTR_P2_L_N")
		)
		(pad "A65" smd rect
			(at 24.500078 0 180)
			(size 0.762 4.2164)
			(layers "F.Cu" "F.Mask" "F.Paste")
			(net "UART_CTS_P2_L_N")
		)
		(pad "A66" smd rect
			(at 25.500076 0 180)
			(size 0.762 4.2164)
			(layers "F.Cu" "F.Mask" "F.Paste")
			(net "GND")
		)
		(pad "A67" smd rect
			(at 26.500074 0 180)
			(size 0.762 4.2164)
			(layers "F.Cu" "F.Mask" "F.Paste")
			(net "Net_2330")
		)
		(pad "A68" smd rect
			(at 27.500072 0 180)
			(size 0.762 4.2164)
			(layers "F.Cu" "F.Mask" "F.Paste")
			(net "Net_2334")
		)
		(pad "A69" smd rect
			(at 28.50007 0 180)
			(size 0.762 4.2164)
			(layers "F.Cu" "F.Mask" "F.Paste")
			(net "Net_2333")
		)
		(pad "A70" smd rect
			(at 29.500068 0 180)
			(size 0.762 4.2164)
			(layers "F.Cu" "F.Mask" "F.Paste")
			(net "GND27")
		)
		(pad "A71" smd rect
			(at 30.500066 0 180)
			(size 0.762 4.2164)
			(layers "F.Cu" "F.Mask" "F.Paste")
			(net "GND")
		)
		(pad "A72" smd rect
			(at 31.500064 0 180)
			(size 0.762 4.2164)
			(layers "F.Cu" "F.Mask" "F.Paste")
			(net "LAN1_P1_P")
		)
		(pad "A73" smd rect
			(at 32.500062 0 180)
			(size 0.762 4.2164)
			(layers "F.Cu" "F.Mask" "F.Paste")
			(net "LAN1_P1_N")
		)
		(pad "A74" smd rect
			(at 33.50006 0 180)
			(size 0.762 4.2164)
			(layers "F.Cu" "F.Mask" "F.Paste")
			(net "GND")
		)
		(pad "A75" smd rect
			(at 34.500058 0 180)
			(size 0.762 4.2164)
			(layers "F.Cu" "F.Mask" "F.Paste")
			(net "LAN1_P2_P")
		)
		(pad "A76" smd rect
			(at 35.500056 0 180)
			(size 0.762 4.2164)
			(layers "F.Cu" "F.Mask" "F.Paste")
			(net "LAN1_P2_N")
		)
		(pad "A77" smd rect
			(at 36.500054 0 180)
			(size 0.762 4.2164)
			(layers "F.Cu" "F.Mask" "F.Paste")
			(net "GND")
		)
		(pad "A78" smd rect
			(at 37.500052 0 180)
			(size 0.762 4.2164)
			(layers "F.Cu" "F.Mask" "F.Paste")
			(net "P12V_PDB")
		)
		(pad "A79" smd rect
			(at 38.50005 0 180)
			(size 0.762 4.2164)
			(layers "F.Cu" "F.Mask" "F.Paste")
			(net "P12V_PDB")
		)
		(pad "A80" smd rect
			(at 39.500048 0 180)
			(size 0.762 4.2164)
			(layers "F.Cu" "F.Mask" "F.Paste")
			(net "P12V_PDB")
		)
		(pad "A81" smd rect
			(at 40.500046 0 180)
			(size 0.762 4.2164)
			(layers "F.Cu" "F.Mask" "F.Paste")
			(net "P12V_PDB")
		)
		(pad "A82" smd rect
			(at 41.500044 0 180)
			(size 0.762 4.2164)
			(layers "F.Cu" "F.Mask" "F.Paste")
			(net "P12V_PDB")
		)
		(pad "B1" smd rect
			(at -41.500044 0 180)
			(size 0.762 4.2164)
			(layers "F.Cu" "F.Mask" "F.Paste")
			(net "GND")
		)
		(pad "B2" smd rect
			(at -40.500046 0 180)
			(size 0.762 4.2164)
			(layers "F.Cu" "F.Mask" "F.Paste")
			(net "UART_T6_NODE2_RXD_R")
		)
		(pad "B3" smd rect
			(at -39.500048 0 180)
			(size 0.762 4.2164)
			(layers "F.Cu" "F.Mask" "F.Paste")
			(net "UART_T6_NODE2_TXD_R")
		)
		(pad "B4" smd rect
			(at -38.50005 0 180)
			(size 0.762 4.2164)
			(layers "F.Cu" "F.Mask" "F.Paste")
			(net "GND")
		)
		(pad "B5" smd rect
			(at -37.500052 0 180)
			(size 0.762 4.2164)
			(layers "F.Cu" "F.Mask" "F.Paste")
			(net "UART_T6_NODE3_RXD_R")
		)
		(pad "B6" smd rect
			(at -36.500054 0 180)
			(size 0.762 4.2164)
			(layers "F.Cu" "F.Mask" "F.Paste")
			(net "UART_T6_NODE3_TXD_R")
		)
		(pad "B7" smd rect
			(at -35.500056 0 180)
			(size 0.762 4.2164)
			(layers "F.Cu" "F.Mask" "F.Paste")
			(net "UART_T6_NODE4_RXD_R")
		)
		(pad "B8" smd rect
			(at -34.500058 0 180)
			(size 0.762 4.2164)
			(layers "F.Cu" "F.Mask" "F.Paste")
			(net "UART_T6_NODE4_TXD_R")
		)
		(pad "B9" smd rect
			(at -33.50006 0 180)
			(size 0.762 4.2164)
			(layers "F.Cu" "F.Mask" "F.Paste")
			(net "GND")
		)
		(pad "B10" smd rect
			(at -32.500062 0 180)
			(size 0.762 4.2164)
			(layers "F.Cu" "F.Mask" "F.Paste")
			(net "I2C_PSU2_R_SCL")
		)
		(pad "B11" smd rect
			(at -31.500064 0 180)
			(size 0.762 4.2164)
			(layers "F.Cu" "F.Mask" "F.Paste")
			(net "I2C_PSU2_R_SDA")
		)
		(pad "B12" smd rect
			(at -28.50007 0 180)
			(size 0.762 4.2164)
			(layers "F.Cu" "F.Mask" "F.Paste")
			(net "T4_NODE1_EN_R")
		)
		(pad "B13" smd rect
			(at -27.500072 0 180)
			(size 0.762 4.2164)
			(layers "F.Cu" "F.Mask" "F.Paste")
			(net "T4_NODE2_EN_R")
		)
		(pad "B14" smd rect
			(at -26.500074 0 180)
			(size 0.762 4.2164)
			(layers "F.Cu" "F.Mask" "F.Paste")
			(net "T4_NODE3_EN_R")
		)
		(pad "B15" smd rect
			(at -25.500076 0 180)
			(size 0.762 4.2164)
			(layers "F.Cu" "F.Mask" "F.Paste")
			(net "T4_NODE4_EN_R")
		)
		(pad "B16" smd rect
			(at -24.500078 0 180)
			(size 0.762 4.2164)
			(layers "F.Cu" "F.Mask" "F.Paste")
			(net "GND")
		)
		(pad "B17" smd rect
			(at -23.50008 -0.499872 180)
			(size 0.762 3.2004)
			(layers "F.Cu" "F.Mask" "F.Paste")
			(net "UART_T4_NODE1_RXD_R")
		)
		(pad "B18" smd rect
			(at -22.500082 0 180)
			(size 0.762 4.2164)
			(layers "F.Cu" "F.Mask" "F.Paste")
			(net "UART_T4_NODE1_TXD_R")
		)
		(pad "B19" smd rect
			(at -21.500084 0 180)
			(size 0.762 4.2164)
			(layers "F.Cu" "F.Mask" "F.Paste")
			(net "UART_T4_NODE2_RXD_R")
		)
		(pad "B20" smd rect
			(at -20.500086 0 180)
			(size 0.762 4.2164)
			(layers "F.Cu" "F.Mask" "F.Paste")
			(net "UART_T4_NODE2_TXD_R")
		)
		(pad "B21" smd rect
			(at -19.500088 0 180)
			(size 0.762 4.2164)
			(layers "F.Cu" "F.Mask" "F.Paste")
			(net "GND")
		)
		(pad "B22" smd rect
			(at -18.50009 0 180)
			(size 0.762 4.2164)
			(layers "F.Cu" "F.Mask" "F.Paste")
			(net "UART_T4_NODE3_RXD_R")
		)
		(pad "B23" smd rect
			(at -17.500092 0 180)
			(size 0.762 4.2164)
			(layers "F.Cu" "F.Mask" "F.Paste")
			(net "UART_T4_NODE3_TXD_R")
		)
		(pad "B24" smd rect
			(at -16.500094 0 180)
			(size 0.762 4.2164)
			(layers "F.Cu" "F.Mask" "F.Paste")
			(net "UART_T4_NODE4_RXD_R")
		)
		(pad "B25" smd rect
			(at -15.500096 0 180)
			(size 0.762 4.2164)
			(layers "F.Cu" "F.Mask" "F.Paste")
			(net "UART_T4_NODE4_TXD_R")
		)
		(pad "B26" smd rect
			(at -14.500098 0 180)
			(size 0.762 4.2164)
			(layers "F.Cu" "F.Mask" "F.Paste")
			(net "GND")
		)
		(pad "B27" smd rect
			(at -13.5001 0 180)
			(size 0.762 4.2164)
			(layers "F.Cu" "F.Mask" "F.Paste")
			(net "T2_NODE1_EN_R")
		)
		(pad "B28" smd rect
			(at -12.500102 0 180)
			(size 0.762 4.2164)
			(layers "F.Cu" "F.Mask" "F.Paste")
			(net "T2_NODE2_EN_R")
		)
		(pad "B29" smd rect
			(at -11.500104 0 180)
			(size 0.762 4.2164)
			(layers "F.Cu" "F.Mask" "F.Paste")
			(net "T2_NODE3_EN_R")
		)
		(pad "B30" smd rect
			(at -10.500106 0 180)
			(size 0.762 4.2164)
			(layers "F.Cu" "F.Mask" "F.Paste")
			(net "T2_NODE4_EN_R")
		)
		(pad "B31" smd rect
			(at -9.500108 -0.499872 180)
			(size 0.762 3.2004)
			(layers "F.Cu" "F.Mask" "F.Paste")
			(net "GND")
		)
		(pad "B32" smd rect
			(at -8.50011 0 180)
			(size 0.762 4.2164)
			(layers "F.Cu" "F.Mask" "F.Paste")
			(net "UART_T2_NODE1_RXD_R")
		)
		(pad "B33" smd rect
			(at -7.500112 0 180)
			(size 0.762 4.2164)
			(layers "F.Cu" "F.Mask" "F.Paste")
			(net "UART_T2_NODE1_TXD_R")
		)
		(pad "B34" smd rect
			(at -6.500114 0 180)
			(size 0.762 4.2164)
			(layers "F.Cu" "F.Mask" "F.Paste")
			(net "UART_T2_NODE2_RXD_R")
		)
		(pad "B35" smd rect
			(at -5.500116 0 180)
			(size 0.762 4.2164)
			(layers "F.Cu" "F.Mask" "F.Paste")
			(net "UART_T2_NODE2_TXD_R")
		)
		(pad "B36" smd rect
			(at -4.500118 0 180)
			(size 0.762 4.2164)
			(layers "F.Cu" "F.Mask" "F.Paste")
			(net "GND")
		)
		(pad "B37" smd rect
			(at -3.50012 0 180)
			(size 0.762 4.2164)
			(layers "F.Cu" "F.Mask" "F.Paste")
			(net "UART_T2_NODE3_RXD_R")
		)
	)
)
